# T6G (Grand Teton) — schematic netlist excerpt (pin names and nets, part order shuffled) for the footprints in the layout excerpt that follows; sources: Cadence DE-HDL packaged netlist, KiCad conversion of 04192023_DAF0TMB3IC0_F0TG_MB_C_brd_V02_OCP.brd

JP6000  CONN3_210HP1030BR1  CONN3_210-HP1-030BR1 IO  pkg HEADER1X3XG  page 171
  \1\  = PU_U212_EN_N
  \2\  = U212_EN_N
  \3\  = PD_U212_EN_N

PC14  Q_CAP  0.1UF 25V 10% X7R  pkg 0402  page 200 : A = PVDDCR_CPU1_P0_VCC ; B = GND
R1406  Q_RES  10K 1% CHIP  pkg 0201LF  page 298 : A = RXDET_BYP_RT_CPU0_P2 ; B = GND

(kicad_pcb
	(version 20260206)
	(generator "pcbnew")
	(generator_version "10.0")
	(general
		(thickness 1.6)
		(legacy_teardrops no)
	)
	(paper "A4")
	(title_block
		(title "04192023_DAF0TMB3IC0_F0TG_MB_C_brd_V02_OCP.brd")
		(comment 1 "Grand Teton / footprints 622-624 of 8354")
	)
	(layers
		(0 "F.Cu" signal "TOP")
		(4 "In1.Cu" signal "GND")
		(6 "In2.Cu" signal "IN1")
		(8 "In3.Cu" signal "GND1")
		(10 "In4.Cu" signal "IN2")
		(12 "In5.Cu" signal "GND2")
		(14 "In6.Cu" signal "IN3")
		(16 "In7.Cu" signal "GND3")
		(18 "In8.Cu" signal "VCC")
		(20 "In9.Cu" signal "VCC1")
		(22 "In10.Cu" signal "GND4")
		(24 "In11.Cu" signal "IN4")
		(26 "In12.Cu" signal "GND5")
		(28 "In13.Cu" signal "IN5")
		(30 "In14.Cu" signal "GND6")
		(32 "In15.Cu" signal "IN6")
		(34 "In16.Cu" signal "GND7")
		(2 "B.Cu" signal "BOTTOM")
		(9 "F.Adhes" user "F.Adhesive")
		(11 "B.Adhes" user "B.Adhesive")
		(13 "F.Paste" user "Package Geometry/Pastemask Top")
		(15 "B.Paste" user "Package Geometry/Pastemask Bottom")
		(5 "F.SilkS" user "Ref Des/Silkscreen Top")
		(7 "B.SilkS" user "Ref Des/Silkscreen Bottom")
		(1 "F.Mask" user "Board Geometry/Soldermask Top")
		(3 "B.Mask" user "Board Geometry/Soldermask Bottom")
		(17 "Dwgs.User" user "User.Drawings")
		(19 "Cmts.User" user "User.Comments")
		(21 "Eco1.User" user "User.Eco1")
		(23 "Eco2.User" user "User.Eco2")
		(25 "Edge.Cuts" user "Board Geometry/Outline")
		(27 "Margin" user)
		(31 "F.CrtYd" user "Package Geometry/Place Bound Top")
		(29 "B.CrtYd" user "Package Geometry/Place Bound Bottom")
		(35 "F.Fab" user "Ref Des/Assembly Top")
		(33 "B.Fab" user "Ref Des/Assembly Bottom")
	)
	(footprint ""
		(layer "F.Cu")
		(at 25.331166 -73.614788 -90)
		(property "Reference" "JP6000"
			(at 2.451354 6.528054 0)
			(unlocked yes)
			(layer "F.SilkS")
			(effects
				(font
					(size 0.7874 0.5842)
					(thickness 0.1524)
				)
				(justify left)
			)
		)
		(property "Value" ""
			(at 0 0 270)
			(layer "F.Fab")
			(effects
				(font
					(size 1.27 1.27)
				)
			)
		)
		(duplicate_pad_numbers_are_jumpers no)
		(fp_line
			(start -1.249934 6.400038)
			(end -1.249934 -1.320038)
			(stroke
				(width 0.1524)
				(type default)
			)
			(layer "F.SilkS")
		)
		(fp_line
			(start 1.249934 6.400038)
			(end -1.249934 6.400038)
			(stroke
				(width 0.1524)
				(type default)
			)
			(layer "F.SilkS")
		)
		(fp_line
			(start -1.249934 -1.320038)
			(end 1.249934 -1.320038)
			(stroke
				(width 0.1524)
				(type default)
			)
			(layer "F.SilkS")
		)
		(fp_line
			(start 1.249934 -1.320038)
			(end 1.249934 6.400038)
			(stroke
				(width 0.1524)
				(type default)
			)
			(layer "F.SilkS")
		)
		(fp_poly
			(pts
				(xy -2.5654 -0.556514) (xy -1.452372 0) (xy -2.5654 0.556514)
			)
			(stroke
				(width 0)
				(type default)
			)
			(fill yes)
			(layer "F.SilkS")
		)
		(fp_line
			(start -1.249934 6.400038)
			(end -1.249934 -1.320038)
			(stroke
				(width 0.1)
				(type default)
			)
			(layer "F.Fab")
		)
		(fp_line
			(start 1.249934 6.400038)
			(end -1.249934 6.400038)
			(stroke
				(width 0.1)
				(type default)
			)
			(layer "F.Fab")
		)
		(fp_line
			(start -1.249934 -1.320038)
			(end 1.249934 -1.320038)
			(stroke
				(width 0.1)
				(type default)
			)
			(layer "F.Fab")
		)
		(fp_line
			(start 1.249934 -1.320038)
			(end 1.249934 6.400038)
			(stroke
				(width 0.1)
				(type default)
			)
			(layer "F.Fab")
		)
		(fp_poly
			(pts
				(xy -2.5654 -0.556514) (xy -1.452372 0) (xy -2.5654 0.556514)
			)
			(stroke
				(width 0)
				(type default)
			)
			(fill yes)
			(layer "F.Fab")
		)
		(fp_text user "3"
			(at -1.778 5.13207 270)
			(unlocked yes)
			(layer "F.SilkS")
			(effects
				(font
					(size 0.7874 0.5842)
					(thickness 0.1524)
				)
			)
		)
		(fp_text user "3"
			(at -1.1557 5.18287 270)
			(unlocked yes)
			(layer "B.SilkS")
			(effects
				(font
					(size 0.7874 0.5842)
					(thickness 0.1524)
				)
				(justify mirror)
			)
		)
		(fp_text user "1"
			(at -1.143 0.02667 270)
			(unlocked yes)
			(layer "B.SilkS")
			(effects
				(font
					(size 0.7874 0.5842)
					(thickness 0.1524)
				)
				(justify mirror)
			)
		)
		(fp_text user "3"
			(at -1.1557 5.18287 270)
			(unlocked yes)
			(layer "B.Fab")
			(effects
				(font
					(size 0.7874 0.5842)
					(thickness 0.1524)
				)
				(justify mirror)
			)
		)
		(fp_text user "1"
			(at -1.143 0.02667 270)
			(unlocked yes)
			(layer "B.Fab")
			(effects
				(font
					(size 0.7874 0.5842)
					(thickness 0.1524)
				)
				(justify mirror)
			)
		)
		(fp_text user "3"
			(at -1.778 5.13207 270)
			(unlocked yes)
			(layer "F.Fab")
			(effects
				(font
					(size 0.7874 0.5842)
					(thickness 0.1524)
				)
			)
		)
		(pad "1" thru_hole rect
			(at 0 0 270)
			(size 1.5494 1.5494)
			(drill 1.0414)
			(layers "*.Cu" "*.Mask")
			(remove_unused_layers no)
			(net "PU_U212_EN_N")
			(clearance 0)
			(padstack
				(mode front_inner_back)
				(layer "Inner"
					(shape circle)
					(size 1.5494 1.5494)
					(clearance 0)
				)
				(layer "B.Cu"
					(shape rect)
					(size 1.5494 1.5494)
					(clearance 0)
				)
			)
		)
		(pad "2" thru_hole circle
			(at 0 2.54 270)
			(size 1.5494 1.5494)
			(drill 1.0414)
			(layers "*.Cu" "*.Mask")
			(remove_unused_layers no)
			(net "U212_EN_N")
			(clearance 0)
		)
		(pad "3" thru_hole circle
			(at 0 5.08 270)
			(size 1.5494 1.5494)
			(drill 1.0414)
			(layers "*.Cu" "*.Mask")
			(remove_unused_layers no)
			(net "PD_U212_EN_N")
			(clearance 0)
		)
	)
	(footprint ""
		(layer "F.Cu")
		(at 316.23 -364.617 90)
		(property "Reference" "PC14"
			(at 0 0 90)
			(layer "F.SilkS")
			(hide yes)
			(effects
				(font
					(size 1.27 1.27)
				)
			)
		)
		(property "Value" ""
			(at 0 0 90)
			(layer "F.Fab")
			(effects
				(font
					(size 1.27 1.27)
				)
			)
		)
		(duplicate_pad_numbers_are_jumpers no)
		(fp_line
			(start 0.7874 -0.4064)
			(end 0.7874 0.4064)
			(stroke
				(width 0.1524)
				(type default)
			)
			(layer "F.SilkS")
		)
		(fp_line
			(start -0.7874 -0.4064)
			(end 0.7874 -0.4064)
			(stroke
				(width 0.1524)
				(type default)
			)
			(layer "F.SilkS")
		)
		(fp_line
			(start 0.7874 0.4064)
			(end -0.7874 0.4064)
			(stroke
				(width 0.1524)
				(type default)
			)
			(layer "F.SilkS")
		)
		(fp_line
			(start -0.7874 0.4064)
			(end -0.7874 -0.4064)
			(stroke
				(width 0.1524)
				(type default)
			)
			(layer "F.SilkS")
		)
		(fp_line
			(start -0.12065 -0.305054)
			(end -0.12065 -0.2794)
			(stroke
				(width 0.1)
				(type default)
			)
			(layer "F.Fab")
		)
		(fp_line
			(start -0.67945 -0.305054)
			(end -0.12065 -0.305054)
			(stroke
				(width 0.1)
				(type default)
			)
			(layer "F.Fab")
		)
		(fp_line
			(start 0.67945 -0.3048)
			(end 0.67945 0.3048)
			(stroke
				(width 0.1)
				(type default)
			)
			(layer "F.Fab")
		)
		(fp_line
			(start 0.12065 -0.3048)
			(end 0.67945 -0.3048)
			(stroke
				(width 0.1)
				(type default)
			)
			(layer "F.Fab")
		)
		(fp_line
			(start 0.12065 -0.2794)
			(end 0.12065 -0.3048)
			(stroke
				(width 0.1)
				(type default)
			)
			(layer "F.Fab")
		)
		(fp_line
			(start -0.12065 -0.2794)
			(end 0.12065 -0.2794)
			(stroke
				(width 0.1)
				(type default)
			)
			(layer "F.Fab")
		)
		(fp_line
			(start 0.120396 0.2794)
			(end -0.12065 0.2794)
			(stroke
				(width 0.1)
				(type default)
			)
			(layer "F.Fab")
		)
		(fp_line
			(start -0.12065 0.2794)
			(end -0.12065 0.3048)
			(stroke
				(width 0.1)
				(type default)
			)
			(layer "F.Fab")
		)
		(fp_line
			(start 0.67945 0.3048)
			(end 0.120396 0.3048)
			(stroke
				(width 0.1)
				(type default)
			)
			(layer "F.Fab")
		)
		(fp_line
			(start 0.120396 0.3048)
			(end 0.120396 0.2794)
			(stroke
				(width 0.1)
				(type default)
			)
			(layer "F.Fab")
		)
		(fp_line
			(start -0.12065 0.3048)
			(end -0.67945 0.3048)
			(stroke
				(width 0.1)
				(type default)
			)
			(layer "F.Fab")
		)
		(fp_line
			(start -0.67945 0.3048)
			(end -0.67945 -0.305054)
			(stroke
				(width 0.1)
				(type default)
			)
			(layer "F.Fab")
		)
		(pad "1" smd circle
			(at -0.40005 0 90)
			(size 0 0)
			(layers "F.Cu" "F.Mask" "F.Paste")
			(net "PVDDCR_CPU1_P0_VCC")
		)
		(pad "2" smd circle
			(at 0.40005 0 90)
			(size 0 0)
			(layers "F.Cu" "F.Mask" "F.Paste")
			(net "GND")
		)
	)
	(footprint ""
		(layer "F.Cu")
		(at 436.052722 -406.33396)
		(property "Reference" "R1406"
			(at 0 0 0)
			(layer "F.SilkS")
			(hide yes)
			(effects
				(font
					(size 1.27 1.27)
				)
			)
		)
		(property "Value" ""
			(at 0 0 0)
			(layer "F.Fab")
			(effects
				(font
					(size 1.27 1.27)
				)
			)
		)
		(duplicate_pad_numbers_are_jumpers no)
		(fp_line
			(start -0.32512 -0.175006)
			(end 0.32512 -0.175006)
			(stroke
				(width 0.1)
				(type default)
			)
			(layer "F.Fab")
		)
		(fp_line
			(start -0.32512 0.175006)
			(end -0.32512 -0.175006)
			(stroke
				(width 0.1)
				(type default)
			)
			(layer "F.Fab")
		)
		(fp_line
			(start 0.32512 -0.175006)
			(end 0.32512 0.175006)
			(stroke
				(width 0.1)
				(type default)
			)
			(layer "F.Fab")
		)
		(fp_line
			(start 0.32512 0.175006)
			(end -0.32512 0.175006)
			(stroke
				(width 0.1)
				(type default)
			)
			(layer "F.Fab")
		)
		(pad "1" smd rect
			(at -0.2667 0)
			(size 0.3048 0.381)
			(layers "F.Cu" "F.Mask" "F.Paste")
			(net "RXDET_BYP_RT_CPU0_P2")
		)
		(pad "2" smd rect
			(at 0.2667 0 180)
			(size 0.3048 0.381)
			(layers "F.Cu" "F.Mask" "F.Paste")
			(net "GND")
		)
	)
)
